# BASEBOARD_FAB2 (Tioga Pass) — schematic netlist excerpt (pin names and nets, part order shuffled) for the footprints in the layout excerpt that follows; sources: Cadence DE-HDL packaged netlist, KiCad conversion of Wiwynn_Tioga_Pass_MB.brd

R2U10  RES  20.0 1% CHIP  pkg 0402  page 159 : A = SMB_OCP_FRU_STBY_LVC3_SDA_R ; B = SMB_OCP_FRU_STBY_LVC3_SDA
C22W7  SC22U16V5MX-4-GP  20%  pkg SMD-BCG5  page 232 : \1\ = VR_FET_SW_P12V_STBY_PVPP_DEF ; \2\ = GND
C3L27  CAP_A  22.0UF 4V 20% X6S  pkg 0603V  page 132 : A = PVNN_PCH_STBY ; B = GND
C9R2  CAP_A  22.0UF 4V 20% X6S  pkg 0603V  page 208 : A = PVCCIN_CPU1 ; B = GND

(kicad_pcb
	(version 20260206)
	(generator "pcbnew")
	(generator_version "10.0")
	(general
		(thickness 1.6)
		(legacy_teardrops no)
	)
	(paper "A4")
	(title_block
		(title "Wiwynn_Tioga_Pass_MB.brd")
		(comment 1 "Tioga Pass / footprints 4689-4692 of 4770")
	)
	(layers
		(0 "F.Cu" signal "TOP")
		(4 "In1.Cu" signal "L2GND")
		(6 "In2.Cu" signal "L3")
		(8 "In3.Cu" signal "L4GND")
		(10 "In4.Cu" signal "L5")
		(12 "In5.Cu" signal "L6GND")
		(14 "In6.Cu" signal "L7VCC")
		(16 "In7.Cu" signal "L8VCC")
		(18 "In8.Cu" signal "L9GND")
		(20 "In9.Cu" signal "L10")
		(22 "In10.Cu" signal "L11GND")
		(24 "In11.Cu" signal "L12")
		(26 "In12.Cu" signal "L13GND")
		(2 "B.Cu" signal "BOTTOM")
		(9 "F.Adhes" user "F.Adhesive")
		(11 "B.Adhes" user "B.Adhesive")
		(13 "F.Paste" user "Package Geometry/Pastemask Top")
		(15 "B.Paste" user "Package Geometry/Pastemask Bottom")
		(5 "F.SilkS" user "Ref Des/Silkscreen Top")
		(7 "B.SilkS" user "Ref Des/Silkscreen Bottom")
		(1 "F.Mask" user "Board Geometry/Soldermask Top")
		(3 "B.Mask" user "Board Geometry/Soldermask Bottom")
		(17 "Dwgs.User" user "User.Drawings")
		(19 "Cmts.User" user "User.Comments")
		(21 "Eco1.User" user "User.Eco1")
		(23 "Eco2.User" user "User.Eco2")
		(25 "Edge.Cuts" user "Board Geometry/Outline")
		(27 "Margin" user)
		(31 "F.CrtYd" user "Package Geometry/Place Bound Top")
		(29 "B.CrtYd" user "Package Geometry/Place Bound Bottom")
		(35 "F.Fab" user "Ref Des/Assembly Top")
		(33 "B.Fab" user "Ref Des/Assembly Bottom")
	)
	(footprint ""
		(layer "B.Cu")
		(at 402.4503 -37.8968 -90)
		(property "Reference" "R2U10"
			(at 0 0 90)
			(layer "B.SilkS")
			(hide yes)
			(effects
				(font
					(size 1.27 1.27)
				)
				(justify mirror)
			)
		)
		(property "Value" ""
			(at 0 0 90)
			(layer "B.Fab")
			(effects
				(font
					(size 1.27 1.27)
				)
				(justify mirror)
			)
		)
		(duplicate_pad_numbers_are_jumpers no)
		(fp_poly
			(pts
				(xy 0.2794 -0.1016) (xy -0.2794 -0.1016) (xy -0.2794 0.9906) (xy 0.2794 0.9906)
			)
			(stroke
				(width 0)
				(type default)
			)
			(fill no)
			(layer "B.CrtYd")
		)
		(fp_line
			(start -0.2794 0.9906)
			(end -0.2794 -0.1016)
			(stroke
				(width 0.1)
				(type default)
			)
			(layer "B.Fab")
		)
		(fp_line
			(start 0.2794 0.9906)
			(end -0.2794 0.9906)
			(stroke
				(width 0.1)
				(type default)
			)
			(layer "B.Fab")
		)
		(fp_line
			(start -0.2794 -0.1016)
			(end 0.2794 -0.1016)
			(stroke
				(width 0.1)
				(type default)
			)
			(layer "B.Fab")
		)
		(fp_line
			(start 0.2794 -0.1016)
			(end 0.2794 0.9906)
			(stroke
				(width 0.1)
				(type default)
			)
			(layer "B.Fab")
		)
		(pad "1" smd rect
			(at 0 0 90)
			(size 0.508 0.508)
			(layers "B.Cu" "B.Mask" "B.Paste")
			(net "SMB_OCP_FRU_STBY_LVC3_SDA_R")
		)
		(pad "2" smd rect
			(at 0 0.889 90)
			(size 0.508 0.508)
			(layers "B.Cu" "B.Mask" "B.Paste")
			(net "SMB_OCP_FRU_STBY_LVC3_SDA")
		)
		(zone
			(layer "B.Cu")
			(hatch none 0.5)
			(connect_pads
				(clearance 0)
			)
			(min_thickness 0.25)
			(keepout
				(tracks not_allowed)
				(vias allowed)
				(pads allowed)
				(copperpour not_allowed)
				(footprints allowed)
			)
			(placement
				(enabled no)
				(sheetname "")
			)
			(fill
				(thermal_gap 0.5)
				(thermal_bridge_width 0.5)
				(island_removal_mode 0)
			)
			(polygon
				(pts
					(xy 401.8153 -37.6428) (xy 401.8153 -38.1508) (xy 402.1963 -38.1508) (xy 402.1963 -37.6428)
				)
			)
		)
		(zone
			(layer "B.Cu")
			(hatch none 0.5)
			(connect_pads
				(clearance 0)
			)
			(min_thickness 0.25)
			(keepout
				(tracks allowed)
				(vias not_allowed)
				(pads allowed)
				(copperpour not_allowed)
				(footprints allowed)
			)
			(placement
				(enabled no)
				(sheetname "")
			)
			(fill
				(thermal_gap 0.5)
				(thermal_bridge_width 0.5)
				(island_removal_mode 0)
			)
			(polygon
				(pts
					(xy 402.1963 -37.6428) (xy 402.1963 -38.1508) (xy 401.8153 -38.1508) (xy 401.8153 -37.6428)
				)
			)
		)
	)
	(footprint ""
		(layer "B.Cu")
		(at 344.59037 -133.92277 180)
		(property "Reference" "C22W7"
			(at 0 0 0)
			(layer "B.SilkS")
			(hide yes)
			(effects
				(font
					(size 1.27 1.27)
				)
				(justify mirror)
			)
		)
		(property "Value" "*"
			(at 0.0762 -6.2357 180)
			(unlocked yes)
			(layer "B.Fab")
			(hide yes)
			(effects
				(font
					(size 1.27 1.016)
					(thickness 0.1524)
				)
				(justify mirror)
			)
		)
		(property "Device Type" "SC22U16V5MX-4-GP_SMD-BCG5-SC22A"
			(at 0.0762 -8.2677 180)
			(unlocked yes)
			(layer "B.Fab")
			(hide yes)
			(effects
				(font
					(size 1.27 1.016)
					(thickness 0.1524)
				)
				(justify mirror)
			)
		)
		(duplicate_pad_numbers_are_jumpers no)
		(fp_line
			(start -0.635 0)
			(end 0.635 0)
			(stroke
				(width 0.508)
				(type default)
			)
			(layer "B.SilkS")
		)
		(fp_rect
			(start 0.9652 1.778)
			(end -0.9652 -1.778)
			(stroke
				(width 0)
				(type default)
			)
			(fill no)
			(layer "B.CrtYd")
		)
		(fp_poly
			(pts
				(xy 0.9652 -1.778) (xy -0.9652 -1.778) (xy -0.9652 1.778) (xy 0.9652 1.778)
			)
			(stroke
				(width 0)
				(type default)
			)
			(fill no)
			(layer "B.Fab")
		)
		(pad "1" smd rect
			(at 0 -0.9652)
			(size 1.397 1.143)
			(layers "B.Cu" "B.Mask" "B.Paste")
			(net "VR_FET_SW_P12V_STBY_PVPP_DEF")
		)
		(pad "2" smd rect
			(at 0 0.9652)
			(size 1.397 1.143)
			(layers "B.Cu" "B.Mask" "B.Paste")
			(net "GND")
		)
	)
	(footprint ""
		(layer "B.Cu")
		(at 380.8476 -137.541)
		(property "Reference" "C3L27"
			(at 0 0 0)
			(layer "B.SilkS")
			(hide yes)
			(effects
				(font
					(size 1.27 1.27)
				)
				(justify mirror)
			)
		)
		(property "Value" ""
			(at 0 0 0)
			(layer "B.Fab")
			(effects
				(font
					(size 1.27 1.27)
				)
				(justify mirror)
			)
		)
		(duplicate_pad_numbers_are_jumpers no)
		(fp_poly
			(pts
				(xy 0.4953 -0.2032) (xy -0.4953 -0.2032) (xy -0.4953 1.6002) (xy 0.4953 1.6002)
			)
			(stroke
				(width 0)
				(type default)
			)
			(fill no)
			(layer "B.CrtYd")
		)
		(fp_line
			(start -0.4953 -0.2032)
			(end -0.4953 1.6002)
			(stroke
				(width 0.1)
				(type default)
			)
			(layer "B.Fab")
		)
		(fp_line
			(start -0.4953 1.6002)
			(end 0.4953 1.6002)
			(stroke
				(width 0.1)
				(type default)
			)
			(layer "B.Fab")
		)
		(fp_line
			(start 0.4953 -0.2032)
			(end -0.4953 -0.2032)
			(stroke
				(width 0.1)
				(type default)
			)
			(layer "B.Fab")
		)
		(fp_line
			(start 0.4953 1.6002)
			(end 0.4953 -0.2032)
			(stroke
				(width 0.1)
				(type default)
			)
			(layer "B.Fab")
		)
		(pad "1" smd rect
			(at 0 0 180)
			(size 0.762 0.889)
			(layers "B.Cu" "B.Mask" "B.Paste")
			(net "PVNN_PCH_STBY")
		)
		(pad "2" smd rect
			(at 0 1.397 180)
			(size 0.762 0.889)
			(layers "B.Cu" "B.Mask" "B.Paste")
			(net "GND")
		)
		(zone
			(layer "B.Cu")
			(hatch none 0.5)
			(connect_pads
				(clearance 0)
			)
			(min_thickness 0.25)
			(keepout
				(tracks not_allowed)
				(vias allowed)
				(pads allowed)
				(copperpour not_allowed)
				(footprints allowed)
			)
			(placement
				(enabled no)
				(sheetname "")
			)
			(fill
				(thermal_gap 0.5)
				(thermal_bridge_width 0.5)
				(island_removal_mode 0)
			)
			(polygon
				(pts
					(xy 381.2286 -137.0965) (xy 380.4666 -137.0965) (xy 380.4666 -136.5885) (xy 381.2286 -136.5885)
				)
			)
		)
	)
	(footprint ""
		(layer "B.Cu")
		(at 49.4284 -63.080392)
		(property "Reference" "C9R2"
			(at 0 0 0)
			(layer "B.SilkS")
			(hide yes)
			(effects
				(font
					(size 1.27 1.27)
				)
				(justify mirror)
			)
		)
		(property "Value" ""
			(at 0 0 0)
			(layer "B.Fab")
			(effects
				(font
					(size 1.27 1.27)
				)
				(justify mirror)
			)
		)
		(duplicate_pad_numbers_are_jumpers no)
		(fp_poly
			(pts
				(xy 0.4953 -0.2032) (xy -0.4953 -0.2032) (xy -0.4953 1.6002) (xy 0.4953 1.6002)
			)
			(stroke
				(width 0)
				(type default)
			)
			(fill no)
			(layer "B.CrtYd")
		)
		(fp_line
			(start -0.4953 -0.2032)
			(end -0.4953 1.6002)
			(stroke
				(width 0.1)
				(type default)
			)
			(layer "B.Fab")
		)
		(fp_line
			(start -0.4953 1.6002)
			(end 0.4953 1.6002)
			(stroke
				(width 0.1)
				(type default)
			)
			(layer "B.Fab")
		)
		(fp_line
			(start 0.4953 -0.2032)
			(end -0.4953 -0.2032)
			(stroke
				(width 0.1)
				(type default)
			)
			(layer "B.Fab")
		)
		(fp_line
			(start 0.4953 1.6002)
			(end 0.4953 -0.2032)
			(stroke
				(width 0.1)
				(type default)
			)
			(layer "B.Fab")
		)
		(pad "1" smd rect
			(at 0 0 180)
			(size 0.762 0.889)
			(layers "B.Cu" "B.Mask" "B.Paste")
			(net "PVCCIN_CPU1")
		)
		(pad "2" smd rect
			(at 0 1.397 180)
			(size 0.762 0.889)
			(layers "B.Cu" "B.Mask" "B.Paste")
			(net "GND")
		)
		(zone
			(layer "B.Cu")
			(hatch none 0.5)
			(connect_pads
				(clearance 0)
			)
			(min_thickness 0.25)
			(keepout
				(tracks not_allowed)
				(vias allowed)
				(pads allowed)
				(copperpour not_allowed)
				(footprints allowed)
			)
			(placement
				(enabled no)
				(sheetname "")
			)
			(fill
				(thermal_gap 0.5)
				(thermal_bridge_width 0.5)
				(island_removal_mode 0)
			)
			(polygon
				(pts
					(xy 49.8094 -62.635892) (xy 49.0474 -62.635892) (xy 49.0474 -62.127892) (xy 49.8094 -62.127892)
				)
			)
		)
	)
)
